#ISCELL
  pure_quanta quanta_title_block_c *
  *
#ISCELL
  pure_quanta_power cad_note *
  *
#CELL
  pure_quanta genoa_sp5 *
  page39_i159
#ISCELL
  mstr_standard offpage *
  page39_i160
#ISCELL
  mstr_standard offpage *
  page39_i161
#ISCELL
  mstr_standard tap *
  page39_i162
#ISCELL
  mstr_standard tap *
  page39_i163
#ISCELL
  mstr_standard tap *
  page39_i164
#ISCELL
  mstr_standard tap *
  page39_i165
#ISCELL
  mstr_standard tap *
  page39_i166
#ISCELL
  mstr_standard tap *
  page39_i167
#ISCELL
  mstr_standard tap *
  page39_i168
#ISCELL
  mstr_standard tap *
  page39_i169
#ISCELL
  mstr_standard tap *
  page39_i170
#ISCELL
  mstr_standard tap *
  page39_i171
#ISCELL
  mstr_standard tap *
  page39_i172
#ISCELL
  mstr_standard tap *
  page39_i173
#ISCELL
  mstr_standard tap *
  page39_i174
#ISCELL
  mstr_standard tap *
  page39_i175
#ISCELL
  mstr_standard tap *
  page39_i176
#ISCELL
  mstr_standard tap *
  page39_i177
#ISCELL
  mstr_standard tap *
  page39_i178
#ISCELL
  mstr_standard tap *
  page39_i179
#ISCELL
  mstr_standard tap *
  page39_i180
#ISCELL
  mstr_standard tap *
  page39_i181
#ISCELL
  mstr_standard tap *
  page39_i182
#ISCELL
  mstr_standard tap *
  page39_i183
#ISCELL
  mstr_standard tap *
  page39_i184
#ISCELL
  mstr_standard tap *
  page39_i185
#ISCELL
  mstr_standard tap *
  page39_i186
#ISCELL
  mstr_standard tap *
  page39_i187
#ISCELL
  mstr_standard tap *
  page39_i188
#ISCELL
  mstr_standard tap *
  page39_i189
#ISCELL
  mstr_standard tap *
  page39_i190
#ISCELL
  mstr_standard tap *
  page39_i191
#ISCELL
  mstr_standard tap *
  page39_i192
#ISCELL
  mstr_standard tap *
  page39_i193
#ISCELL
  mstr_standard tap *
  page39_i194
#ISCELL
  mstr_standard tap *
  page39_i195
#ISCELL
  mstr_standard tap *
  page39_i196
#ISCELL
  mstr_standard tap *
  page39_i197
#ISCELL
  mstr_standard offpage *
  page39_i198
#ISCELL
  mstr_standard tap *
  page39_i199
#ISCELL
  mstr_standard tap *
  page39_i200
#ISCELL
  mstr_standard tap *
  page39_i201
#ISCELL
  mstr_standard tap *
  page39_i202
#ISCELL
  mstr_standard tap *
  page39_i203
#ISCELL
  mstr_standard tap *
  page39_i204
#ISCELL
  mstr_standard tap *
  page39_i205
#ISCELL
  mstr_standard tap *
  page39_i206
#ISCELL
  mstr_standard tap *
  page39_i207
#ISCELL
  mstr_standard tap *
  page39_i208
#ISCELL
  mstr_standard tap *
  page39_i209
#ISCELL
  mstr_standard tap *
  page39_i210
#ISCELL
  mstr_standard tap *
  page39_i211
#ISCELL
  mstr_standard tap *
  page39_i212
#ISCELL
  mstr_standard tap *
  page39_i213
#ISCELL
  mstr_standard tap *
  page39_i214
#ISCELL
  mstr_standard tap *
  page39_i215
#ISCELL
  mstr_standard tap *
  page39_i216
#ISCELL
  mstr_standard tap *
  page39_i217
#ISCELL
  mstr_standard tap *
  page39_i218
#ISCELL
  mstr_standard tap *
  page39_i219
#ISCELL
  mstr_standard tap *
  page39_i220
#ISCELL
  mstr_standard tap *
  page39_i221
#ISCELL
  mstr_standard tap *
  page39_i222
#ISCELL
  mstr_standard tap *
  page39_i223
#ISCELL
  mstr_standard tap *
  page39_i224
#ISCELL
  mstr_standard tap *
  page39_i225
#ISCELL
  mstr_standard tap *
  page39_i226
#ISCELL
  mstr_standard tap *
  page39_i227
#ISCELL
  mstr_standard tap *
  page39_i228
#ISCELL
  mstr_standard tap *
  page39_i229
#ISCELL
  mstr_standard tap *
  page39_i230
#ISCELL
  mstr_standard tap *
  page39_i231
#ISCELL
  mstr_standard tap *
  page39_i232
#ISCELL
  mstr_standard tap *
  page39_i233
#ISCELL
  mstr_standard tap *
  page39_i234
#ISCELL
  mstr_standard offpage *
  page39_i235
#ISCELL
  mstr_standard tap *
  page39_i236
#ISCELL
  mstr_standard tap *
  page39_i237
#ISCELL
  mstr_standard tap *
  page39_i238
#ISCELL
  mstr_standard tap *
  page39_i239
#ISCELL
  mstr_standard tap *
  page39_i240
#ISCELL
  mstr_standard tap *
  page39_i241
#ISCELL
  mstr_standard tap *
  page39_i242
#ISCELL
  mstr_standard tap *
  page39_i243
#ISCELL
  mstr_standard tap *
  page39_i244
#ISCELL
  mstr_standard tap *
  page39_i245
#ISCELL
  mstr_standard tap *
  page39_i246
#ISCELL
  mstr_standard tap *
  page39_i247
#ISCELL
  mstr_standard tap *
  page39_i248
#ISCELL
  mstr_standard tap *
  page39_i249
#ISCELL
  mstr_standard tap *
  page39_i250
#ISCELL
  mstr_standard tap *
  page39_i251
#ISCELL
  mstr_standard tap *
  page39_i252
#ISCELL
  mstr_standard tap *
  page39_i253
#ISCELL
  mstr_standard tap *
  page39_i254
#ISCELL
  mstr_standard tap *
  page39_i255
#ISCELL
  mstr_standard tap *
  page39_i256
#ISCELL
  mstr_standard tap *
  page39_i257
#ISCELL
  mstr_standard tap *
  page39_i258
#ISCELL
  mstr_standard tap *
  page39_i259
#ISCELL
  mstr_standard tap *
  page39_i260
#ISCELL
  mstr_standard tap *
  page39_i261
#ISCELL
  mstr_standard tap *
  page39_i262
#ISCELL
  mstr_standard tap *
  page39_i263
#ISCELL
  mstr_standard tap *
  page39_i264
#ISCELL
  mstr_standard tap *
  page39_i265
#ISCELL
  mstr_standard tap *
  page39_i266
#ISCELL
  mstr_standard tap *
  page39_i267
#ISCELL
  mstr_standard tap *
  page39_i268
#ISCELL
  mstr_standard tap *
  page39_i269
#ISCELL
  mstr_standard tap *
  page39_i270
#ISCELL
  mstr_standard tap *
  page39_i271
#ISCELL
  mstr_standard tap *
  page39_i272
#ISCELL
  mstr_standard tap *
  page39_i273
#ISCELL
  mstr_standard tap *
  page39_i274
#ISCELL
  mstr_standard tap *
  page39_i275
#ISCELL
  mstr_standard tap *
  page39_i276
#ISCELL
  mstr_standard tap *
  page39_i277
#ISCELL
  mstr_standard tap *
  page39_i278
#ISCELL
  mstr_standard tap *
  page39_i279
#ISCELL
  mstr_standard tap *
  page39_i280
#ISCELL
  mstr_standard tap *
  page39_i281
#ISCELL
  mstr_standard tap *
  page39_i282
#ISCELL
  standard offpage *
  page39_i283
#ISCELL
  standard offpage *
  page39_i284
#ISCELL
  standard offpage *
  page39_i285
#ISCELL
  standard offpage *
  page39_i286
#ISCELL
  mstr_standard tap *
  page39_i287
#ISCELL
  mstr_standard tap *
  page39_i288
#ISCELL
  mstr_standard tap *
  page39_i289
#ISCELL
  mstr_standard tap *
  page39_i290
#ISCELL
  mstr_standard tap *
  page39_i291
#ISCELL
  mstr_standard tap *
  page39_i292
#ISCELL
  mstr_standard tap *
  page39_i293
#ISCELL
  mstr_standard tap *
  page39_i294
#ISCELL
  mstr_standard tap *
  page39_i295
#ISCELL
  mstr_standard tap *
  page39_i296
#ISCELL
  mstr_standard tap *
  page39_i297
#ISCELL
  mstr_standard tap *
  page39_i298
#ISCELL
  mstr_standard tap *
  page39_i299
#ISCELL
  mstr_standard tap *
  page39_i300
#ISCELL
  mstr_standard tap *
  page39_i301
#ISCELL
  standard offpage *
  page39_i302
#ISCELL
  standard offpage *
  page39_i303
#ISCELL
  standard offpage *
  page39_i304
#ISCELL
  standard offpage *
  page39_i305
#ISCELL
  standard offpage *
  page39_i306
#ISCELL
  standard offpage *
  page39_i307
#ISCELL
  standard offpage *
  page39_i308
#ISCELL
  mstr_standard offpage *
  page39_i309
#ISCELL
  standard offpage *
  page39_i310
#ISCELL
  standard offpage *
  page39_i311
#ISCELL
  standard offpage *
  page39_i312
#CELL
  pure_quanta q_res *
  page39_i313
#ISCELL
  standard offpage *
  page39_i314
#ISCELL
  standard offpage *
  page39_i315
#ISCELL
  mstr_standard offpage *
  page39_i316
